(kicad_pcb
	(version 20241229)
	(generator "pcbnew")
	(generator_version "9.0")
	(general
		(thickness 1.62)
		(legacy_teardrops no)
	)
	(paper "A3")
	(title_block
		(title "COM Express 7 Baseboard")
		(date "2025-02-04")
		(rev "1.1.2")
		(company "Antmicro Ltd")
		(comment 1 "www.antmicro.com")
		(comment 9 "footprints 627-630 of 802")
	)
	(layers
		(0 "F.Cu" signal)
		(4 "In1.Cu" signal)
		(6 "In2.Cu" signal)
		(8 "In3.Cu" signal)
		(10 "In4.Cu" signal)
		(12 "In5.Cu" signal)
		(14 "In6.Cu" signal)
		(2 "B.Cu" signal)
		(9 "F.Adhes" user "F.Adhesive")
		(11 "B.Adhes" user "B.Adhesive")
		(13 "F.Paste" user)
		(15 "B.Paste" user)
		(5 "F.SilkS" user "F.Silkscreen")
		(7 "B.SilkS" user "B.Silkscreen")
		(1 "F.Mask" user)
		(3 "B.Mask" user)
		(17 "Dwgs.User" user "User.Drawings")
		(19 "Cmts.User" user "User.Comments")
		(21 "Eco1.User" user "User.Eco1")
		(23 "Eco2.User" user "User.Eco2")
		(25 "Edge.Cuts" user)
		(27 "Margin" user)
		(31 "F.CrtYd" user "F.Courtyard")
		(29 "B.CrtYd" user "B.Courtyard")
		(35 "F.Fab" user)
		(33 "B.Fab" user)
	)
	(footprint "antmicro-footprints:R_0402_1005Metric"
		(layer "B.Cu")
		(at 123.4 95.86 180)
		(descr "Resistor SMD 0402")
		(tags "resistor SMD 0402")
		(property "Reference" "R331"
			(at -3.7 -0.41 0)
			(layer "B.SilkS")
			(effects
				(font
					(size 0.7 0.7)
					(thickness 0.15)
				)
				(justify left bottom mirror)
			)
		)
		(property "Value" "R_470R_0402"
			(at -1.011843 -1.772047 0)
			(layer "B.Fab")
			(effects
				(font
					(size 0.7 0.7)
					(thickness 0.15)
				)
				(justify left bottom mirror)
			)
		)
		(property "Datasheet" "https://www.bourns.com/docs/product-datasheets/cr.pdf"
			(at 0 0 0)
			(layer "B.Fab")
			(hide yes)
			(effects
				(font
					(size 1.27 1.27)
					(thickness 0.15)
				)
				(justify mirror)
			)
		)
		(property "MPN" "CR0402-FX-4700GLF"
			(at 0 0 0)
			(unlocked yes)
			(layer "B.Fab")
			(hide yes)
			(effects
				(font
					(size 1 1)
					(thickness 0.15)
				)
				(justify mirror)
			)
		)
		(property "Manufacturer" "Bourns"
			(at 0 0 0)
			(unlocked yes)
			(layer "B.Fab")
			(hide yes)
			(effects
				(font
					(size 1 1)
					(thickness 0.15)
				)
				(justify mirror)
			)
		)
		(property "License" "Apache-2.0"
			(at 0 0 0)
			(unlocked yes)
			(layer "B.Fab")
			(hide yes)
			(effects
				(font
					(size 1 1)
					(thickness 0.15)
				)
				(justify mirror)
			)
		)
		(property "Author" "Antmicro"
			(at 0 0 0)
			(unlocked yes)
			(layer "B.Fab")
			(hide yes)
			(effects
				(font
					(size 1 1)
					(thickness 0.15)
				)
				(justify mirror)
			)
		)
		(property "Val" "470R"
			(at 0 0 0)
			(unlocked yes)
			(layer "B.Fab")
			(hide yes)
			(effects
				(font
					(size 1 1)
					(thickness 0.15)
				)
				(justify mirror)
			)
		)
		(property "Tolerance" "1%"
			(at 0 0 0)
			(unlocked yes)
			(layer "B.Fab")
			(hide yes)
			(effects
				(font
					(size 1 1)
					(thickness 0.15)
				)
				(justify mirror)
			)
		)
		(property "Public" "False"
			(at 0 0 0)
			(unlocked yes)
			(layer "B.Fab")
			(hide yes)
			(effects
				(font
					(size 1 1)
					(thickness 0.15)
				)
				(justify mirror)
			)
		)
		(sheetname "2xUSB3.0+RJ45")
		(sheetfile "usb3+rj45.kicad_sch")
		(attr smd dnp)
		(fp_rect
			(start -0.925 0.47)
			(end 0.925 -0.47)
			(stroke
				(width 0.05)
				(type default)
			)
			(fill no)
			(layer "B.CrtYd")
		)
		(fp_rect
			(start -0.5 0.25)
			(end 0.5 -0.25)
			(stroke
				(width 0.15)
				(type solid)
			)
			(fill no)
			(layer "B.Fab")
		)
		(pad "1" smd roundrect
			(at -0.48 0 180)
			(size 0.59 0.64)
			(layers "B.Cu" "B.Mask" "B.Paste")
			(roundrect_rratio 0.25)
			(net 1 "GND")
			(pintype "passive")
			(teardrops
				(best_length_ratio 0.2)
				(max_length 1)
				(best_width_ratio 0.9)
				(max_width 2)
				(curved_edges yes)
				(filter_ratio 0.9)
				(enabled yes)
				(allow_two_segments yes)
				(prefer_zone_connections yes)
			)
		)
		(pad "2" smd roundrect
			(at 0.48 0 180)
			(size 0.59 0.64)
			(layers "B.Cu" "B.Mask" "B.Paste")
			(roundrect_rratio 0.25)
			(net 154 "Net-(J1A-LED_D1)")
			(pintype "passive")
			(teardrops
				(best_length_ratio 0.2)
				(max_length 1)
				(best_width_ratio 0.9)
				(max_width 2)
				(curved_edges yes)
				(filter_ratio 0.9)
				(enabled yes)
				(allow_two_segments yes)
				(prefer_zone_connections yes)
			)
		)
	)
	(footprint "antmicro-footprints:C_0402_1005Metric"
		(layer "B.Cu")
		(at 218.25 127.324)
		(descr "Capacitor SMD 0402")
		(tags "capacitor SMD 0402")
		(property "Reference" "C103"
			(at -1.4 -0.464 0)
			(layer "B.SilkS")
			(effects
				(font
					(size 0.7 0.7)
					(thickness 0.15)
				)
				(justify right bottom mirror)
			)
		)
		(property "Value" "C_100n_0402"
			(at -1.022927 -2.155213 0)
			(layer "B.Fab")
			(effects
				(font
					(size 0.7 0.7)
					(thickness 0.15)
				)
				(justify right bottom mirror)
			)
		)
		(property "Datasheet" "https://www.murata.com/products/productdetail?partno=GRM155R61H104KE14%23"
			(at 0 0 0)
			(layer "F.Fab")
			(hide yes)
			(effects
				(font
					(size 1.27 1.27)
					(thickness 0.15)
				)
			)
		)
		(property "Author" "Antmicro"
			(at 0 0 0)
			(layer "B.Fab")
			(hide yes)
			(effects
				(font
					(size 1 1)
					(thickness 0.15)
				)
				(justify mirror)
			)
		)
		(property "Dielectric" "X5R"
			(at 0 0 0)
			(layer "B.Fab")
			(hide yes)
			(effects
				(font
					(size 1 1)
					(thickness 0.15)
				)
				(justify mirror)
			)
		)
		(property "License" "Apache-2.0"
			(at 0 0 0)
			(layer "B.Fab")
			(hide yes)
			(effects
				(font
					(size 1 1)
					(thickness 0.15)
				)
				(justify mirror)
			)
		)
		(property "MPN" "GRM155R61H104KE14D"
			(at 0 0 0)
			(layer "B.Fab")
			(hide yes)
			(effects
				(font
					(size 1 1)
					(thickness 0.15)
				)
				(justify mirror)
			)
		)
		(property "Manufacturer" "Murata"
			(at 0 0 0)
			(layer "B.Fab")
			(hide yes)
			(effects
				(font
					(size 1 1)
					(thickness 0.15)
				)
				(justify mirror)
			)
		)
		(property "Public" "False"
			(at 0 0 0)
			(layer "B.Fab")
			(hide yes)
			(effects
				(font
					(size 1 1)
					(thickness 0.15)
				)
				(justify mirror)
			)
		)
		(property "Val" "100n"
			(at 0 0 0)
			(layer "B.Fab")
			(hide yes)
			(effects
				(font
					(size 1 1)
					(thickness 0.15)
				)
				(justify mirror)
			)
		)
		(property "Voltage" "50V"
			(at 0 0 0)
			(layer "B.Fab")
			(hide yes)
			(effects
				(font
					(size 1 1)
					(thickness 0.15)
				)
				(justify mirror)
			)
		)
		(sheetname "PCIe misc")
		(sheetfile "pcie_misc.kicad_sch")
		(attr smd)
		(fp_rect
			(start -0.925 0.47)
			(end 0.925 -0.47)
			(stroke
				(width 0.05)
				(type default)
			)
			(fill no)
			(layer "B.CrtYd")
		)
		(fp_line
			(start -0.494 -0.248)
			(end 0.504 -0.248)
			(stroke
				(width 0.15)
				(type solid)
			)
			(layer "B.Fab")
		)
		(fp_line
			(start -0.494 0.25)
			(end -0.494 -0.248)
			(stroke
				(width 0.15)
				(type solid)
			)
			(layer "B.Fab")
		)
		(fp_line
			(start 0.504 -0.248)
			(end 0.504 0.25)
			(stroke
				(width 0.15)
				(type solid)
			)
			(layer "B.Fab")
		)
		(fp_line
			(start 0.504 0.25)
			(end -0.494 0.25)
			(stroke
				(width 0.15)
				(type solid)
			)
			(layer "B.Fab")
		)
		(pad "1" smd roundrect
			(at -0.48 0)
			(size 0.59 0.64)
			(layers "B.Cu" "B.Mask" "B.Paste")
			(roundrect_rratio 0.25)
			(net 1 "GND")
			(pintype "passive")
			(teardrops
				(best_length_ratio 0.2)
				(max_length 1)
				(best_width_ratio 0.9)
				(max_width 2)
				(curved_edges yes)
				(filter_ratio 0.9)
				(enabled yes)
				(allow_two_segments yes)
				(prefer_zone_connections yes)
			)
		)
		(pad "2" smd roundrect
			(at 0.48 0)
			(size 0.59 0.64)
			(layers "B.Cu" "B.Mask" "B.Paste")
			(roundrect_rratio 0.25)
			(net 2 "+3V3")
			(pintype "passive")
			(teardrops
				(best_length_ratio 0.2)
				(max_length 1)
				(best_width_ratio 0.9)
				(max_width 2)
				(curved_edges yes)
				(filter_ratio 0.9)
				(enabled yes)
				(allow_two_segments yes)
				(prefer_zone_connections yes)
			)
		)
	)
	(footprint "antmicro-footprints:R_0402_1005Metric"
		(layer "B.Cu")
		(at 107.5 163.01 180)
		(descr "Resistor SMD 0402")
		(tags "resistor SMD 0402")
		(property "Reference" "R83"
			(at -3 -0.43 0)
			(layer "B.SilkS")
			(effects
				(font
					(size 0.7 0.7)
					(thickness 0.15)
				)
				(justify left bottom mirror)
			)
		)
		(property "Value" "R_0R_0402"
			(at -1.011843 -1.772047 0)
			(layer "B.Fab")
			(effects
				(font
					(size 0.7 0.7)
					(thickness 0.15)
				)
				(justify left bottom mirror)
			)
		)
		(property "Datasheet" "https://industrial.panasonic.com/cdbs/www-data/pdf/RDA0000/AOA0000C301.pdf"
			(at 0 0 180)
			(layer "F.Fab")
			(hide yes)
			(effects
				(font
					(size 1.27 1.27)
					(thickness 0.15)
				)
			)
		)
		(property "Author" "Antmicro"
			(at 215 326.02 0)
			(layer "B.Fab")
			(hide yes)
			(effects
				(font
					(size 1 1)
					(thickness 0.15)
				)
				(justify mirror)
			)
		)
		(property "Current" "1A"
			(at 215 326.02 0)
			(layer "B.Fab")
			(hide yes)
			(effects
				(font
					(size 1 1)
					(thickness 0.15)
				)
				(justify mirror)
			)
		)
		(property "License" "Apache-2.0"
			(at 215 326.02 0)
			(layer "B.Fab")
			(hide yes)
			(effects
				(font
					(size 1 1)
					(thickness 0.15)
				)
				(justify mirror)
			)
		)
		(property "MPN" "ERJ2GE0R00X"
			(at 215 326.02 0)
			(layer "B.Fab")
			(hide yes)
			(effects
				(font
					(size 1 1)
					(thickness 0.15)
				)
				(justify mirror)
			)
		)
		(property "Manufacturer" "Panasonic"
			(at 215 326.02 0)
			(layer "B.Fab")
			(hide yes)
			(effects
				(font
					(size 1 1)
					(thickness 0.15)
				)
				(justify mirror)
			)
		)
		(property "Public" "False"
			(at 215 326.02 0)
			(layer "B.Fab")
			(hide yes)
			(effects
				(font
					(size 1 1)
					(thickness 0.15)
				)
				(justify mirror)
			)
		)
		(property "Tolerance" ""
			(at 215 326.02 0)
			(layer "B.Fab")
			(hide yes)
			(effects
				(font
					(size 1 1)
					(thickness 0.15)
				)
				(justify mirror)
			)
		)
		(property "Val" "0R"
			(at 215 326.02 0)
			(layer "B.Fab")
			(hide yes)
			(effects
				(font
					(size 1 1)
					(thickness 0.15)
				)
				(justify mirror)
			)
		)
		(sheetname "OCuLink")
		(sheetfile "oculink.kicad_sch")
		(attr smd)
		(fp_rect
			(start -0.925 0.47)
			(end 0.925 -0.47)
			(stroke
				(width 0.05)
				(type default)
			)
			(fill no)
			(layer "B.CrtYd")
		)
		(fp_rect
			(start -0.5 0.25)
			(end 0.5 -0.25)
			(stroke
				(width 0.15)
				(type solid)
			)
			(fill no)
			(layer "B.Fab")
		)
		(pad "1" smd roundrect
			(at -0.48 0 180)
			(size 0.59 0.64)
			(layers "B.Cu" "B.Mask" "B.Paste")
			(roundrect_rratio 0.25)
			(net 357 "/Com Express 7 MGMT/SMBus.SCL")
			(pintype "passive")
			(teardrops
				(best_length_ratio 0.2)
				(max_length 1)
				(best_width_ratio 0.9)
				(max_width 2)
				(curved_edges yes)
				(filter_ratio 0.9)
				(enabled yes)
				(allow_two_segments yes)
				(prefer_zone_connections yes)
			)
		)
		(pad "2" smd roundrect
			(at 0.48 0 180)
			(size 0.59 0.64)
			(layers "B.Cu" "B.Mask" "B.Paste")
			(roundrect_rratio 0.25)
			(net 198 "/OCuLink/SCL")
			(pintype "passive")
			(teardrops
				(best_length_ratio 0.2)
				(max_length 1)
				(best_width_ratio 0.9)
				(max_width 2)
				(curved_edges yes)
				(filter_ratio 0.9)
				(enabled yes)
				(allow_two_segments yes)
				(prefer_zone_connections yes)
			)
		)
	)
	(footprint "antmicro-footprints:R_0402_1005Metric"
		(layer "B.Cu")
		(at 310.5 118.16 90)
		(descr "Resistor SMD 0402")
		(tags "resistor SMD 0402")
		(property "Reference" "R95"
			(at -1 -0.45 90)
			(layer "B.SilkS")
			(effects
				(font
					(size 0.7 0.7)
					(thickness 0.15)
				)
				(justify right bottom mirror)
			)
		)
		(property "Value" "R_10k_0402"
			(at -1.011843 -1.772047 90)
			(layer "B.Fab")
			(effects
				(font
					(size 0.7 0.7)
					(thickness 0.15)
				)
				(justify right bottom mirror)
			)
		)
		(property "Datasheet" "https://www.bourns.com/docs/product-datasheets/cr.pdf"
			(at 0 0 90)
			(layer "F.Fab")
			(hide yes)
			(effects
				(font
					(size 1.27 1.27)
					(thickness 0.15)
				)
			)
		)
		(property "Author" "Antmicro"
			(at 428.66 -192.34 0)
			(layer "B.Fab")
			(hide yes)
			(effects
				(font
					(size 1 1)
					(thickness 0.15)
				)
				(justify mirror)
			)
		)
		(property "License" "Apache-2.0"
			(at 428.66 -192.34 0)
			(layer "B.Fab")
			(hide yes)
			(effects
				(font
					(size 1 1)
					(thickness 0.15)
				)
				(justify mirror)
			)
		)
		(property "MPN" "CR0402-FX-1002GLF"
			(at 428.66 -192.34 0)
			(layer "B.Fab")
			(hide yes)
			(effects
				(font
					(size 1 1)
					(thickness 0.15)
				)
				(justify mirror)
			)
		)
		(property "Manufacturer" "Bourns"
			(at 428.66 -192.34 0)
			(layer "B.Fab")
			(hide yes)
			(effects
				(font
					(size 1 1)
					(thickness 0.15)
				)
				(justify mirror)
			)
		)
		(property "Public" "False"
			(at 428.66 -192.34 0)
			(layer "B.Fab")
			(hide yes)
			(effects
				(font
					(size 1 1)
					(thickness 0.15)
				)
				(justify mirror)
			)
		)
		(property "Tolerance" "1%"
			(at 428.66 -192.34 0)
			(layer "B.Fab")
			(hide yes)
			(effects
				(font
					(size 1 1)
					(thickness 0.15)
				)
				(justify mirror)
			)
		)
		(property "Val" "10k"
			(at 428.66 -192.34 0)
			(layer "B.Fab")
			(hide yes)
			(effects
				(font
					(size 1 1)
					(thickness 0.15)
				)
				(justify mirror)
			)
		)
		(sheetname "Power")
		(sheetfile "power.kicad_sch")
		(attr smd)
		(fp_rect
			(start -0.925 0.47)
			(end 0.925 -0.47)
			(stroke
				(width 0.05)
				(type default)
			)
			(fill no)
			(layer "B.CrtYd")
		)
		(fp_rect
			(start -0.5 0.25)
			(end 0.5 -0.25)
			(stroke
				(width 0.15)
				(type solid)
			)
			(fill no)
			(layer "B.Fab")
		)
		(pad "1" smd roundrect
			(at -0.48 0 90)
			(size 0.59 0.64)
			(layers "B.Cu" "B.Mask" "B.Paste")
			(roundrect_rratio 0.25)
			(net 578 "/Power/PG_{1V0}")
			(pintype "passive")
			(teardrops
				(best_length_ratio 0.2)
				(max_length 1)
				(best_width_ratio 0.9)
				(max_width 2)
				(curved_edges yes)
				(filter_ratio 0.9)
				(enabled yes)
				(allow_two_segments yes)
				(prefer_zone_connections yes)
			)
		)
		(pad "2" smd roundrect
			(at 0.48 0 90)
			(size 0.59 0.64)
			(layers "B.Cu" "B.Mask" "B.Paste")
			(roundrect_rratio 0.25)
			(net 2 "+3V3")
			(pintype "passive")
			(teardrops
				(best_length_ratio 0.2)
				(max_length 1)
				(best_width_ratio 0.9)
				(max_width 2)
				(curved_edges yes)
				(filter_ratio 0.9)
				(enabled yes)
				(allow_two_segments yes)
				(prefer_zone_connections yes)
			)
		)
	)
)
